(kicad_pcb
	(version 20221018)
	(generator pcbnew)
	(general
    (thickness 1.7403)
  )
	(paper "A4")
	(title_block
    (title "Data Center RDIMM DDR4 Tester")
    (date "2024-09-30")
    (rev "1.2.4")
		(comment 9 "footprints 504-513 of 690")
	)
	(layers
    (0 "F.Cu" signal)
    (1 "In1.Cu" power)
    (2 "In2.Cu" signal)
    (3 "In3.Cu" power)
    (4 "In4.Cu" power)
    (5 "In5.Cu" signal)
    (6 "In6.Cu" power)
    (7 "In7.Cu" signal)
    (8 "In8.Cu" power)
    (9 "In9.Cu" signal)
    (10 "In10.Cu" power)
    (31 "B.Cu" signal)
    (32 "B.Adhes" user "B.Adhesive")
    (33 "F.Adhes" user "F.Adhesive")
    (34 "B.Paste" user)
    (35 "F.Paste" user)
    (36 "B.SilkS" user "B.Silkscreen")
    (37 "F.SilkS" user "F.Silkscreen")
    (38 "B.Mask" user)
    (39 "F.Mask" user)
    (40 "Dwgs.User" user "User.Drawings")
    (41 "Cmts.User" user "User.Comments")
    (42 "Eco1.User" user "User.Eco1")
    (43 "Eco2.User" user "User.Eco2")
    (44 "Edge.Cuts" user)
    (45 "Margin" user)
    (46 "B.CrtYd" user "B.Courtyard")
    (47 "F.CrtYd" user "F.Courtyard")
    (48 "B.Fab" user)
    (49 "F.Fab" user)
  )
	(footprint "data-center-rdimm-ddr4-tester-footprints:C_0402_1005Metric" (layer "B.Cu")
    (at 187.986328 54.760008 90)
    (descr "Capacitor SMD 0402")
    (tags "capacitor SMD 0402")
    (property "Author" "Antmicro")
    (property "Dielectric" "X5R")
    (property "License" "Apache-2.0")
    (property "MPN" "GRM155R61H104KE14D")
    (property "Manufacturer" "Murata")
    (property "Sheetfile" "DDR4.kicad_sch")
    (property "Sheetname" "DDR4")
    (property "Val" "100n")
    (property "Voltage" "50V")
    (property "ki_description" " ")
    (attr smd)
    (fp_text reference "C162" (at 4.050008 0.423672 270) (layer "B.SilkS")
        (effects (font (size 0.7 0.7) (thickness 0.15)) (justify left bottom mirror))
    )
    (fp_text value "C_100n_0402" (at 0 -1.4 270) (layer "B.Fab") hide
        (effects (font (size 0.7 0.7) (thickness 0.15)) (justify left bottom mirror))
    )
    (fp_text user "License: Apache-2.0" (at -0.932 -5.17 270) (layer "B.Fab") hide
        (effects (font (size 0.7 0.7) (thickness 0.15)) (justify left bottom mirror))
    )
    (fp_text user "Author: Antmicro" (at -0.932 -4.17 270) (layer "B.Fab") hide
        (effects (font (size 0.7 0.7) (thickness 0.15)) (justify left bottom mirror))
    )
    (fp_text user "${REFERENCE}" (at -0.932 -3.168 270) (layer "B.Fab") hide
        (effects (font (size 0.7 0.7) (thickness 0.15)) (justify left bottom mirror))
    )
    (fp_rect (start -0.94 0.47) (end 0.94 -0.47)
      (stroke (width 0.05) (type solid)) (fill none) (layer "B.CrtYd"))
    (fp_rect (start -0.499 0.249) (end 0.499 -0.249)
      (stroke (width 0.15) (type solid)) (fill none) (layer "B.Fab"))
    (pad "1" smd roundrect (at -0.484 0 90) (size 0.59 0.64) (layers "B.Cu" "B.Paste" "B.Mask") (roundrect_rratio 0.25)
      (net 77 "VDDQ") (pintype "passive"))
    (pad "2" smd roundrect (at 0.484 0 90) (size 0.59 0.64) (layers "B.Cu" "B.Paste" "B.Mask") (roundrect_rratio 0.25)
      (net 9 "GND") (pintype "passive"))
  )
	(footprint "data-center-rdimm-ddr4-tester-footprints:C_0402_1005Metric" (layer "B.Cu")
    (at 185.436328 54.760008 90)
    (descr "Capacitor SMD 0402")
    (tags "capacitor SMD 0402")
    (property "Author" "Antmicro")
    (property "Dielectric" "X5R")
    (property "License" "Apache-2.0")
    (property "MPN" "GRM155R61H104KE14D")
    (property "Manufacturer" "Murata")
    (property "Sheetfile" "DDR4.kicad_sch")
    (property "Sheetname" "DDR4")
    (property "Val" "100n")
    (property "Voltage" "50V")
    (property "ki_description" " ")
    (attr smd)
    (fp_text reference "C163" (at 4.050008 0.423672 270) (layer "B.SilkS")
        (effects (font (size 0.7 0.7) (thickness 0.15)) (justify left bottom mirror))
    )
    (fp_text value "C_100n_0402" (at 0 -1.4 270) (layer "B.Fab") hide
        (effects (font (size 0.7 0.7) (thickness 0.15)) (justify left bottom mirror))
    )
    (fp_text user "License: Apache-2.0" (at -0.932 -5.17 270) (layer "B.Fab") hide
        (effects (font (size 0.7 0.7) (thickness 0.15)) (justify left bottom mirror))
    )
    (fp_text user "Author: Antmicro" (at -0.932 -4.17 270) (layer "B.Fab") hide
        (effects (font (size 0.7 0.7) (thickness 0.15)) (justify left bottom mirror))
    )
    (fp_text user "${REFERENCE}" (at -0.932 -3.168 270) (layer "B.Fab") hide
        (effects (font (size 0.7 0.7) (thickness 0.15)) (justify left bottom mirror))
    )
    (fp_rect (start -0.94 0.47) (end 0.94 -0.47)
      (stroke (width 0.05) (type solid)) (fill none) (layer "B.CrtYd"))
    (fp_rect (start -0.499 0.249) (end 0.499 -0.249)
      (stroke (width 0.15) (type solid)) (fill none) (layer "B.Fab"))
    (pad "1" smd roundrect (at -0.484 0 90) (size 0.59 0.64) (layers "B.Cu" "B.Paste" "B.Mask") (roundrect_rratio 0.25)
      (net 77 "VDDQ") (pintype "passive"))
    (pad "2" smd roundrect (at 0.484 0 90) (size 0.59 0.64) (layers "B.Cu" "B.Paste" "B.Mask") (roundrect_rratio 0.25)
      (net 9 "GND") (pintype "passive"))
  )
	(footprint "data-center-rdimm-ddr4-tester-footprints:C_0402_1005Metric" (layer "B.Cu")
    (at 171.836328 55.060008 90)
    (descr "Capacitor SMD 0402")
    (tags "capacitor SMD 0402")
    (property "Author" "Antmicro")
    (property "Dielectric" "X5R")
    (property "License" "Apache-2.0")
    (property "MPN" "GRM155R61H104KE14D")
    (property "Manufacturer" "Murata")
    (property "Sheetfile" "DDR4.kicad_sch")
    (property "Sheetname" "DDR4")
    (property "Val" "100n")
    (property "Voltage" "50V")
    (property "ki_description" " ")
    (attr smd)
    (fp_text reference "C166" (at 4.350008 0.363672 270) (layer "B.SilkS")
        (effects (font (size 0.7 0.7) (thickness 0.15)) (justify left bottom mirror))
    )
    (fp_text value "C_100n_0402" (at 0 -1.4 270) (layer "B.Fab") hide
        (effects (font (size 0.7 0.7) (thickness 0.15)) (justify left bottom mirror))
    )
    (fp_text user "License: Apache-2.0" (at -0.932 -5.17 270) (layer "B.Fab") hide
        (effects (font (size 0.7 0.7) (thickness 0.15)) (justify left bottom mirror))
    )
    (fp_text user "Author: Antmicro" (at -0.932 -4.17 270) (layer "B.Fab") hide
        (effects (font (size 0.7 0.7) (thickness 0.15)) (justify left bottom mirror))
    )
    (fp_text user "${REFERENCE}" (at -0.932 -3.168 270) (layer "B.Fab") hide
        (effects (font (size 0.7 0.7) (thickness 0.15)) (justify left bottom mirror))
    )
    (fp_rect (start -0.94 0.47) (end 0.94 -0.47)
      (stroke (width 0.05) (type solid)) (fill none) (layer "B.CrtYd"))
    (fp_rect (start -0.499 0.249) (end 0.499 -0.249)
      (stroke (width 0.15) (type solid)) (fill none) (layer "B.Fab"))
    (pad "1" smd roundrect (at -0.484 0 90) (size 0.59 0.64) (layers "B.Cu" "B.Paste" "B.Mask") (roundrect_rratio 0.25)
      (net 77 "VDDQ") (pintype "passive"))
    (pad "2" smd roundrect (at 0.484 0 90) (size 0.59 0.64) (layers "B.Cu" "B.Paste" "B.Mask") (roundrect_rratio 0.25)
      (net 9 "GND") (pintype "passive"))
  )
	(footprint "data-center-rdimm-ddr4-tester-footprints:C_0402_1005Metric" (layer "B.Cu")
    (at 170.136328 55.060008 90)
    (descr "Capacitor SMD 0402")
    (tags "capacitor SMD 0402")
    (property "Author" "Antmicro")
    (property "Dielectric" "X5R")
    (property "License" "Apache-2.0")
    (property "MPN" "GRM155R61H104KE14D")
    (property "Manufacturer" "Murata")
    (property "Sheetfile" "DDR4.kicad_sch")
    (property "Sheetname" "DDR4")
    (property "Val" "100n")
    (property "Voltage" "50V")
    (property "ki_description" " ")
    (attr smd)
    (fp_text reference "C167" (at 4.350008 0.363672 270) (layer "B.SilkS")
        (effects (font (size 0.7 0.7) (thickness 0.15)) (justify left bottom mirror))
    )
    (fp_text value "C_100n_0402" (at 0 -1.4 270) (layer "B.Fab") hide
        (effects (font (size 0.7 0.7) (thickness 0.15)) (justify left bottom mirror))
    )
    (fp_text user "Author: Antmicro" (at -0.932 -4.17 270) (layer "B.Fab") hide
        (effects (font (size 0.7 0.7) (thickness 0.15)) (justify left bottom mirror))
    )
    (fp_text user "License: Apache-2.0" (at -0.932 -5.17 270) (layer "B.Fab") hide
        (effects (font (size 0.7 0.7) (thickness 0.15)) (justify left bottom mirror))
    )
    (fp_text user "${REFERENCE}" (at -0.932 -3.168 270) (layer "B.Fab") hide
        (effects (font (size 0.7 0.7) (thickness 0.15)) (justify left bottom mirror))
    )
    (fp_rect (start -0.94 0.47) (end 0.94 -0.47)
      (stroke (width 0.05) (type solid)) (fill none) (layer "B.CrtYd"))
    (fp_rect (start -0.499 0.249) (end 0.499 -0.249)
      (stroke (width 0.15) (type solid)) (fill none) (layer "B.Fab"))
    (pad "1" smd roundrect (at -0.484 0 90) (size 0.59 0.64) (layers "B.Cu" "B.Paste" "B.Mask") (roundrect_rratio 0.25)
      (net 77 "VDDQ") (pintype "passive"))
    (pad "2" smd roundrect (at 0.484 0 90) (size 0.59 0.64) (layers "B.Cu" "B.Paste" "B.Mask") (roundrect_rratio 0.25)
      (net 9 "GND") (pintype "passive"))
  )
	(footprint "data-center-rdimm-ddr4-tester-footprints:C_0402_1005Metric" (layer "B.Cu")
    (at 167.586328 55.060008 90)
    (descr "Capacitor SMD 0402")
    (tags "capacitor SMD 0402")
    (property "Author" "Antmicro")
    (property "Dielectric" "X5R")
    (property "License" "Apache-2.0")
    (property "MPN" "GRM155R61H104KE14D")
    (property "Manufacturer" "Murata")
    (property "Sheetfile" "DDR4.kicad_sch")
    (property "Sheetname" "DDR4")
    (property "Val" "100n")
    (property "Voltage" "50V")
    (property "ki_description" " ")
    (attr smd)
    (fp_text reference "C168" (at 4.350008 0.363672 270) (layer "B.SilkS")
        (effects (font (size 0.7 0.7) (thickness 0.15)) (justify left bottom mirror))
    )
    (fp_text value "C_100n_0402" (at 0 -1.4 270) (layer "B.Fab") hide
        (effects (font (size 0.7 0.7) (thickness 0.15)) (justify left bottom mirror))
    )
    (fp_text user "Author: Antmicro" (at -0.932 -4.17 270) (layer "B.Fab") hide
        (effects (font (size 0.7 0.7) (thickness 0.15)) (justify left bottom mirror))
    )
    (fp_text user "License: Apache-2.0" (at -0.932 -5.17 270) (layer "B.Fab") hide
        (effects (font (size 0.7 0.7) (thickness 0.15)) (justify left bottom mirror))
    )
    (fp_text user "${REFERENCE}" (at -0.932 -3.168 270) (layer "B.Fab") hide
        (effects (font (size 0.7 0.7) (thickness 0.15)) (justify left bottom mirror))
    )
    (fp_rect (start -0.94 0.47) (end 0.94 -0.47)
      (stroke (width 0.05) (type solid)) (fill none) (layer "B.CrtYd"))
    (fp_rect (start -0.499 0.249) (end 0.499 -0.249)
      (stroke (width 0.15) (type solid)) (fill none) (layer "B.Fab"))
    (pad "1" smd roundrect (at -0.484 0 90) (size 0.59 0.64) (layers "B.Cu" "B.Paste" "B.Mask") (roundrect_rratio 0.25)
      (net 77 "VDDQ") (pintype "passive"))
    (pad "2" smd roundrect (at 0.484 0 90) (size 0.59 0.64) (layers "B.Cu" "B.Paste" "B.Mask") (roundrect_rratio 0.25)
      (net 9 "GND") (pintype "passive"))
  )
	(footprint "data-center-rdimm-ddr4-tester-footprints:C_0402_1005Metric" (layer "B.Cu")
    (at 165.886328 55.060008 90)
    (descr "Capacitor SMD 0402")
    (tags "capacitor SMD 0402")
    (property "Author" "Antmicro")
    (property "Dielectric" "X5R")
    (property "License" "Apache-2.0")
    (property "MPN" "GRM155R61H104KE14D")
    (property "Manufacturer" "Murata")
    (property "Sheetfile" "DDR4.kicad_sch")
    (property "Sheetname" "DDR4")
    (property "Val" "100n")
    (property "Voltage" "50V")
    (property "ki_description" " ")
    (attr smd)
    (fp_text reference "C169" (at 4.350008 0.363672 270) (layer "B.SilkS")
        (effects (font (size 0.7 0.7) (thickness 0.15)) (justify left bottom mirror))
    )
    (fp_text value "C_100n_0402" (at 0 -1.4 270) (layer "B.Fab") hide
        (effects (font (size 0.7 0.7) (thickness 0.15)) (justify left bottom mirror))
    )
    (fp_text user "Author: Antmicro" (at -0.932 -4.17 270) (layer "B.Fab") hide
        (effects (font (size 0.7 0.7) (thickness 0.15)) (justify left bottom mirror))
    )
    (fp_text user "${REFERENCE}" (at -0.932 -3.168 270) (layer "B.Fab") hide
        (effects (font (size 0.7 0.7) (thickness 0.15)) (justify left bottom mirror))
    )
    (fp_text user "License: Apache-2.0" (at -0.932 -5.17 270) (layer "B.Fab") hide
        (effects (font (size 0.7 0.7) (thickness 0.15)) (justify left bottom mirror))
    )
    (fp_rect (start -0.94 0.47) (end 0.94 -0.47)
      (stroke (width 0.05) (type solid)) (fill none) (layer "B.CrtYd"))
    (fp_rect (start -0.499 0.249) (end 0.499 -0.249)
      (stroke (width 0.15) (type solid)) (fill none) (layer "B.Fab"))
    (pad "1" smd roundrect (at -0.484 0 90) (size 0.59 0.64) (layers "B.Cu" "B.Paste" "B.Mask") (roundrect_rratio 0.25)
      (net 77 "VDDQ") (pintype "passive"))
    (pad "2" smd roundrect (at 0.484 0 90) (size 0.59 0.64) (layers "B.Cu" "B.Paste" "B.Mask") (roundrect_rratio 0.25)
      (net 9 "GND") (pintype "passive"))
  )
	(footprint "data-center-rdimm-ddr4-tester-footprints:C_0402_1005Metric" (layer "B.Cu")
    (at 164.186328 55.060008 90)
    (descr "Capacitor SMD 0402")
    (tags "capacitor SMD 0402")
    (property "Author" "Antmicro")
    (property "Dielectric" "X5R")
    (property "License" "Apache-2.0")
    (property "MPN" "GRM155R61H104KE14D")
    (property "Manufacturer" "Murata")
    (property "Sheetfile" "DDR4.kicad_sch")
    (property "Sheetname" "DDR4")
    (property "Val" "100n")
    (property "Voltage" "50V")
    (property "ki_description" " ")
    (attr smd)
    (fp_text reference "C170" (at 4.350008 0.363672 270) (layer "B.SilkS")
        (effects (font (size 0.7 0.7) (thickness 0.15)) (justify left bottom mirror))
    )
    (fp_text value "C_100n_0402" (at 0 -1.4 270) (layer "B.Fab") hide
        (effects (font (size 0.7 0.7) (thickness 0.15)) (justify left bottom mirror))
    )
    (fp_text user "Author: Antmicro" (at -0.932 -4.17 270) (layer "B.Fab") hide
        (effects (font (size 0.7 0.7) (thickness 0.15)) (justify left bottom mirror))
    )
    (fp_text user "${REFERENCE}" (at -0.932 -3.168 270) (layer "B.Fab") hide
        (effects (font (size 0.7 0.7) (thickness 0.15)) (justify left bottom mirror))
    )
    (fp_text user "License: Apache-2.0" (at -0.932 -5.17 270) (layer "B.Fab") hide
        (effects (font (size 0.7 0.7) (thickness 0.15)) (justify left bottom mirror))
    )
    (fp_rect (start -0.94 0.47) (end 0.94 -0.47)
      (stroke (width 0.05) (type solid)) (fill none) (layer "B.CrtYd"))
    (fp_rect (start -0.499 0.249) (end 0.499 -0.249)
      (stroke (width 0.15) (type solid)) (fill none) (layer "B.Fab"))
    (pad "1" smd roundrect (at -0.484 0 90) (size 0.59 0.64) (layers "B.Cu" "B.Paste" "B.Mask") (roundrect_rratio 0.25)
      (net 77 "VDDQ") (pintype "passive"))
    (pad "2" smd roundrect (at 0.484 0 90) (size 0.59 0.64) (layers "B.Cu" "B.Paste" "B.Mask") (roundrect_rratio 0.25)
      (net 9 "GND") (pintype "passive"))
  )
	(footprint "data-center-rdimm-ddr4-tester-footprints:C_0402_1005Metric" (layer "B.Cu")
    (at 164.186328 59.660008 -90)
    (descr "Capacitor SMD 0402")
    (tags "capacitor SMD 0402")
    (property "Author" "Antmicro")
    (property "Dielectric" "X5R")
    (property "License" "Apache-2.0")
    (property "MPN" "GRM155R61H104KE14D")
    (property "Manufacturer" "Murata")
    (property "Sheetfile" "DDR4.kicad_sch")
    (property "Sheetname" "DDR4")
    (property "Val" "100n")
    (property "Voltage" "50V")
    (property "ki_description" " ")
    (attr smd)
    (fp_text reference "C171" (at -1.420008 0.536328 90) (layer "B.SilkS")
        (effects (font (size 0.7 0.7) (thickness 0.15)) (justify left bottom mirror))
    )
    (fp_text value "C_100n_0402" (at 0 -1.4 90) (layer "B.Fab") hide
        (effects (font (size 0.7 0.7) (thickness 0.15)) (justify left bottom mirror))
    )
    (fp_text user "${REFERENCE}" (at -0.932 -3.168 90) (layer "B.Fab") hide
        (effects (font (size 0.7 0.7) (thickness 0.15)) (justify left bottom mirror))
    )
    (fp_text user "Author: Antmicro" (at -0.932 -4.17 90) (layer "B.Fab") hide
        (effects (font (size 0.7 0.7) (thickness 0.15)) (justify left bottom mirror))
    )
    (fp_text user "License: Apache-2.0" (at -0.932 -5.17 90) (layer "B.Fab") hide
        (effects (font (size 0.7 0.7) (thickness 0.15)) (justify left bottom mirror))
    )
    (fp_rect (start -0.94 0.47) (end 0.94 -0.47)
      (stroke (width 0.05) (type solid)) (fill none) (layer "B.CrtYd"))
    (fp_rect (start -0.499 0.249) (end 0.499 -0.249)
      (stroke (width 0.15) (type solid)) (fill none) (layer "B.Fab"))
    (pad "1" smd roundrect (at -0.484 0 270) (size 0.59 0.64) (layers "B.Cu" "B.Paste" "B.Mask") (roundrect_rratio 0.25)
      (net 77 "VDDQ") (pintype "passive"))
    (pad "2" smd roundrect (at 0.484 0 270) (size 0.59 0.64) (layers "B.Cu" "B.Paste" "B.Mask") (roundrect_rratio 0.25)
      (net 9 "GND") (pintype "passive"))
  )
	(footprint "data-center-rdimm-ddr4-tester-footprints:C_0402_1005Metric" (layer "B.Cu")
    (at 165.036328 57.610008 180)
    (descr "Capacitor SMD 0402")
    (tags "capacitor SMD 0402")
    (property "Author" "Antmicro")
    (property "Dielectric" "X5R")
    (property "License" "Apache-2.0")
    (property "MPN" "GRM155R61H104KE14D")
    (property "Manufacturer" "Murata")
    (property "Sheetfile" "DDR4.kicad_sch")
    (property "Sheetname" "DDR4")
    (property "Val" "100n")
    (property "Voltage" "50V")
    (property "ki_description" " ")
    (attr smd)
    (fp_text reference "C173" (at 1.056328 -0.349992) (layer "B.SilkS")
        (effects (font (size 0.7 0.7) (thickness 0.15)) (justify left bottom mirror))
    )
    (fp_text value "C_100n_0402" (at 0 -1.4) (layer "B.Fab") hide
        (effects (font (size 0.7 0.7) (thickness 0.15)) (justify left bottom mirror))
    )
    (fp_text user "${REFERENCE}" (at -0.932 -3.168) (layer "B.Fab") hide
        (effects (font (size 0.7 0.7) (thickness 0.15)) (justify left bottom mirror))
    )
    (fp_text user "License: Apache-2.0" (at -0.932 -5.17) (layer "B.Fab") hide
        (effects (font (size 0.7 0.7) (thickness 0.15)) (justify left bottom mirror))
    )
    (fp_text user "Author: Antmicro" (at -0.932 -4.17) (layer "B.Fab") hide
        (effects (font (size 0.7 0.7) (thickness 0.15)) (justify left bottom mirror))
    )
    (fp_rect (start -0.94 0.47) (end 0.94 -0.47)
      (stroke (width 0.05) (type solid)) (fill none) (layer "B.CrtYd"))
    (fp_rect (start -0.499 0.249) (end 0.499 -0.249)
      (stroke (width 0.15) (type solid)) (fill none) (layer "B.Fab"))
    (pad "1" smd roundrect (at -0.484 0 180) (size 0.59 0.64) (layers "B.Cu" "B.Paste" "B.Mask") (roundrect_rratio 0.25)
      (net 77 "VDDQ") (pintype "passive"))
    (pad "2" smd roundrect (at 0.484 0 180) (size 0.59 0.64) (layers "B.Cu" "B.Paste" "B.Mask") (roundrect_rratio 0.25)
      (net 9 "GND") (pintype "passive"))
  )
	(footprint "data-center-rdimm-ddr4-tester-footprints:C_0402_1005Metric" (layer "B.Cu")
    (at 170.136328 59.660008 -90)
    (descr "Capacitor SMD 0402")
    (tags "capacitor SMD 0402")
    (property "Author" "Antmicro")
    (property "Dielectric" "X5R")
    (property "License" "Apache-2.0")
    (property "MPN" "GRM155R61H104KE14D")
    (property "Manufacturer" "Murata")
    (property "Sheetfile" "DDR4.kicad_sch")
    (property "Sheetname" "DDR4")
    (property "Val" "100n")
    (property "Voltage" "50V")
    (property "ki_description" " ")
    (attr smd)
    (fp_text reference "C177" (at 0.809992 -0.363672 90) (layer "B.SilkS")
        (effects (font (size 0.7 0.7) (thickness 0.15)) (justify left bottom mirror))
    )
    (fp_text value "C_100n_0402" (at 0 -1.4 90) (layer "B.Fab") hide
        (effects (font (size 0.7 0.7) (thickness 0.15)) (justify left bottom mirror))
    )
    (fp_text user "License: Apache-2.0" (at -0.932 -5.17 90) (layer "B.Fab") hide
        (effects (font (size 0.7 0.7) (thickness 0.15)) (justify left bottom mirror))
    )
    (fp_text user "${REFERENCE}" (at -0.932 -3.168 90) (layer "B.Fab") hide
        (effects (font (size 0.7 0.7) (thickness 0.15)) (justify left bottom mirror))
    )
    (fp_text user "Author: Antmicro" (at -0.932 -4.17 90) (layer "B.Fab") hide
        (effects (font (size 0.7 0.7) (thickness 0.15)) (justify left bottom mirror))
    )
    (fp_rect (start -0.94 0.47) (end 0.94 -0.47)
      (stroke (width 0.05) (type solid)) (fill none) (layer "B.CrtYd"))
    (fp_rect (start -0.499 0.249) (end 0.499 -0.249)
      (stroke (width 0.15) (type solid)) (fill none) (layer "B.Fab"))
    (pad "1" smd roundrect (at -0.484 0 270) (size 0.59 0.64) (layers "B.Cu" "B.Paste" "B.Mask") (roundrect_rratio 0.25)
      (net 77 "VDDQ") (pintype "passive"))
    (pad "2" smd roundrect (at 0.484 0 270) (size 0.59 0.64) (layers "B.Cu" "B.Paste" "B.Mask") (roundrect_rratio 0.25)
      (net 9 "GND") (pintype "passive"))
  )
)
